(kicad_pcb
	(version 20260206)
	(generator "pcbnew")
	(generator_version "10.0")
	(general
		(thickness 1.6)
		(legacy_teardrops no)
	)
	(paper "A4")
	(title_block
		(title "Wiwynn_Tioga_Pass_MB.brd")
		(comment 1 "Tioga Pass / footprints 977-984 of 4770")
	)
	(layers
		(0 "F.Cu" signal "TOP")
		(4 "In1.Cu" signal "L2GND")
		(6 "In2.Cu" signal "L3")
		(8 "In3.Cu" signal "L4GND")
		(10 "In4.Cu" signal "L5")
		(12 "In5.Cu" signal "L6GND")
		(14 "In6.Cu" signal "L7VCC")
		(16 "In7.Cu" signal "L8VCC")
		(18 "In8.Cu" signal "L9GND")
		(20 "In9.Cu" signal "L10")
		(22 "In10.Cu" signal "L11GND")
		(24 "In11.Cu" signal "L12")
		(26 "In12.Cu" signal "L13GND")
		(2 "B.Cu" signal "BOTTOM")
		(9 "F.Adhes" user "F.Adhesive")
		(11 "B.Adhes" user "B.Adhesive")
		(13 "F.Paste" user "Package Geometry/Pastemask Top")
		(15 "B.Paste" user "Package Geometry/Pastemask Bottom")
		(5 "F.SilkS" user "Ref Des/Silkscreen Top")
		(7 "B.SilkS" user "Ref Des/Silkscreen Bottom")
		(1 "F.Mask" user "Board Geometry/Soldermask Top")
		(3 "B.Mask" user "Board Geometry/Soldermask Bottom")
		(17 "Dwgs.User" user "User.Drawings")
		(19 "Cmts.User" user "User.Comments")
		(21 "Eco1.User" user "User.Eco1")
		(23 "Eco2.User" user "User.Eco2")
		(25 "Edge.Cuts" user "Board Geometry/Outline")
		(27 "Margin" user)
		(31 "F.CrtYd" user "Package Geometry/Place Bound Top")
		(29 "B.CrtYd" user "Package Geometry/Place Bound Bottom")
		(35 "F.Fab" user "Ref Des/Assembly Top")
		(33 "B.Fab" user "Ref Des/Assembly Bottom")
	)
	(footprint ""
		(layer "F.Cu")
		(at 28.702 -3.766312)
		(property "Reference" "R1G15"
			(at 0 0 0)
			(layer "F.SilkS")
			(hide yes)
			(effects
				(font
					(size 1.27 1.27)
				)
			)
		)
		(property "Value" ""
			(at 0 0 0)
			(layer "F.Fab")
			(effects
				(font
					(size 1.27 1.27)
				)
			)
		)
		(duplicate_pad_numbers_are_jumpers no)
		(fp_poly
			(pts
				(xy -0.2794 -0.1016) (xy 0.2794 -0.1016) (xy 0.2794 0.9906) (xy -0.2794 0.9906)
			)
			(stroke
				(width 0)
				(type default)
			)
			(fill no)
			(layer "F.CrtYd")
		)
		(fp_line
			(start -0.2794 -0.1016)
			(end -0.2794 0.9906)
			(stroke
				(width 0.1)
				(type default)
			)
			(layer "F.Fab")
		)
		(fp_line
			(start -0.2794 0.9906)
			(end 0.2794 0.9906)
			(stroke
				(width 0.1)
				(type default)
			)
			(layer "F.Fab")
		)
		(fp_line
			(start 0.2794 -0.1016)
			(end -0.2794 -0.1016)
			(stroke
				(width 0.1)
				(type default)
			)
			(layer "F.Fab")
		)
		(fp_line
			(start 0.2794 0.9906)
			(end 0.2794 -0.1016)
			(stroke
				(width 0.1)
				(type default)
			)
			(layer "F.Fab")
		)
		(pad "1" smd rect
			(at 0 0)
			(size 0.508 0.508)
			(layers "F.Cu" "F.Mask" "F.Paste")
			(net "PVDDQ_GHJ")
		)
		(pad "2" smd rect
			(at 0 0.889)
			(size 0.508 0.508)
			(layers "F.Cu" "F.Mask" "F.Paste")
			(net "M_J_VREF")
		)
		(zone
			(layer "F.Cu")
			(hatch none 0.5)
			(connect_pads
				(clearance 0)
			)
			(min_thickness 0.25)
			(keepout
				(tracks allowed)
				(vias not_allowed)
				(pads allowed)
				(copperpour not_allowed)
				(footprints allowed)
			)
			(placement
				(enabled no)
				(sheetname "")
			)
			(fill
				(thermal_gap 0.5)
				(thermal_bridge_width 0.5)
				(island_removal_mode 0)
			)
			(polygon
				(pts
					(xy 28.448 -3.512312) (xy 28.956 -3.512312) (xy 28.956 -3.131312) (xy 28.448 -3.131312)
				)
			)
		)
		(zone
			(layer "F.Cu")
			(hatch none 0.5)
			(connect_pads
				(clearance 0)
			)
			(min_thickness 0.25)
			(keepout
				(tracks not_allowed)
				(vias allowed)
				(pads allowed)
				(copperpour not_allowed)
				(footprints allowed)
			)
			(placement
				(enabled no)
				(sheetname "")
			)
			(fill
				(thermal_gap 0.5)
				(thermal_bridge_width 0.5)
				(island_removal_mode 0)
			)
			(polygon
				(pts
					(xy 28.448 -3.131312) (xy 28.956 -3.131312) (xy 28.956 -3.512312) (xy 28.448 -3.512312)
				)
			)
		)
	)
	(footprint ""
		(layer "F.Cu")
		(at 13.8938 -34.798 90)
		(property "Reference" "C1F4"
			(at 0 0 90)
			(layer "F.SilkS")
			(hide yes)
			(effects
				(font
					(size 1.27 1.27)
				)
			)
		)
		(property "Value" ""
			(at 0 0 90)
			(layer "F.Fab")
			(effects
				(font
					(size 1.27 1.27)
				)
			)
		)
		(duplicate_pad_numbers_are_jumpers no)
		(fp_rect
			(start -0.3048 -0.1016)
			(end 0.3048 0.9906)
			(stroke
				(width 0)
				(type default)
			)
			(fill no)
			(layer "F.CrtYd")
		)
		(fp_line
			(start 0.3048 -0.1016)
			(end -0.3048 -0.1016)
			(stroke
				(width 0.1)
				(type default)
			)
			(layer "F.Fab")
		)
		(fp_line
			(start -0.3048 -0.1016)
			(end -0.3048 0.9906)
			(stroke
				(width 0.1)
				(type default)
			)
			(layer "F.Fab")
		)
		(fp_line
			(start 0.3048 0.9906)
			(end 0.3048 -0.1016)
			(stroke
				(width 0.1)
				(type default)
			)
			(layer "F.Fab")
		)
		(fp_line
			(start -0.3048 0.9906)
			(end 0.3048 0.9906)
			(stroke
				(width 0.1)
				(type default)
			)
			(layer "F.Fab")
		)
		(pad "1" smd rect
			(at 0 0 90)
			(size 0.508 0.508)
			(layers "F.Cu" "F.Mask" "F.Paste")
			(net "P3E_CPU1_PE3_MP_C_TXN<6>")
		)
		(pad "2" smd rect
			(at 0 0.889 90)
			(size 0.508 0.508)
			(layers "F.Cu" "F.Mask" "F.Paste")
			(net "P3E_CPU1_PE3_MP_TXN<6>")
		)
		(zone
			(layer "F.Cu")
			(hatch none 0.5)
			(connect_pads
				(clearance 0)
			)
			(min_thickness 0.25)
			(keepout
				(tracks not_allowed)
				(vias allowed)
				(pads allowed)
				(copperpour not_allowed)
				(footprints allowed)
			)
			(placement
				(enabled no)
				(sheetname "")
			)
			(fill
				(thermal_gap 0.5)
				(thermal_bridge_width 0.5)
				(island_removal_mode 0)
			)
			(polygon
				(pts
					(xy 14.1478 -34.544) (xy 14.5288 -34.544) (xy 14.5288 -35.052) (xy 14.1478 -35.052)
				)
			)
		)
		(zone
			(layer "F.Cu")
			(hatch none 0.5)
			(connect_pads
				(clearance 0)
			)
			(min_thickness 0.25)
			(keepout
				(tracks allowed)
				(vias not_allowed)
				(pads allowed)
				(copperpour not_allowed)
				(footprints allowed)
			)
			(placement
				(enabled no)
				(sheetname "")
			)
			(fill
				(thermal_gap 0.5)
				(thermal_bridge_width 0.5)
				(island_removal_mode 0)
			)
			(polygon
				(pts
					(xy 14.1478 -34.544) (xy 14.5288 -34.544) (xy 14.5288 -35.052) (xy 14.1478 -35.052)
				)
			)
		)
	)
	(footprint ""
		(layer "F.Cu")
		(at 368.69624 -107.106466)
		(property "Reference" "C7C5"
			(at 0 0 0)
			(layer "F.SilkS")
			(hide yes)
			(effects
				(font
					(size 1.27 1.27)
				)
			)
		)
		(property "Value" ""
			(at 0 0 0)
			(layer "F.Fab")
			(effects
				(font
					(size 1.27 1.27)
				)
			)
		)
		(duplicate_pad_numbers_are_jumpers no)
		(fp_poly
			(pts
				(xy 0.3048 -0.1016) (xy 0.3048 0.9906) (xy -0.3048 0.9906) (xy -0.3048 -0.1016)
			)
			(stroke
				(width 0)
				(type default)
			)
			(fill no)
			(layer "F.CrtYd")
		)
		(fp_line
			(start -0.3048 -0.1016)
			(end -0.3048 0.9906)
			(stroke
				(width 0.1)
				(type default)
			)
			(layer "F.Fab")
		)
		(fp_line
			(start -0.3048 0.9906)
			(end 0.3048 0.9906)
			(stroke
				(width 0.1)
				(type default)
			)
			(layer "F.Fab")
		)
		(fp_line
			(start 0.3048 -0.1016)
			(end -0.3048 -0.1016)
			(stroke
				(width 0.1)
				(type default)
			)
			(layer "F.Fab")
		)
		(fp_line
			(start 0.3048 0.9906)
			(end 0.3048 -0.1016)
			(stroke
				(width 0.1)
				(type default)
			)
			(layer "F.Fab")
		)
		(pad "1" smd rect
			(at 0 0)
			(size 0.508 0.508)
			(layers "F.Cu" "F.Mask" "F.Paste")
			(net "XTAL_PCH_48M_OUT")
		)
		(pad "2" smd rect
			(at 0 0.889)
			(size 0.508 0.508)
			(layers "F.Cu" "F.Mask" "F.Paste")
			(net "GND")
		)
		(zone
			(layer "F.Cu")
			(hatch none 0.5)
			(connect_pads
				(clearance 0)
			)
			(min_thickness 0.25)
			(keepout
				(tracks allowed)
				(vias not_allowed)
				(pads allowed)
				(copperpour not_allowed)
				(footprints allowed)
			)
			(placement
				(enabled no)
				(sheetname "")
			)
			(fill
				(thermal_gap 0.5)
				(thermal_bridge_width 0.5)
				(island_removal_mode 0)
			)
			(polygon
				(pts
					(xy 368.44224 -106.852466) (xy 368.95024 -106.852466) (xy 368.95024 -106.471466) (xy 368.44224 -106.471466)
				)
			)
		)
		(zone
			(layer "F.Cu")
			(hatch none 0.5)
			(connect_pads
				(clearance 0)
			)
			(min_thickness 0.25)
			(keepout
				(tracks not_allowed)
				(vias allowed)
				(pads allowed)
				(copperpour not_allowed)
				(footprints allowed)
			)
			(placement
				(enabled no)
				(sheetname "")
			)
			(fill
				(thermal_gap 0.5)
				(thermal_bridge_width 0.5)
				(island_removal_mode 0)
			)
			(polygon
				(pts
					(xy 368.44224 -106.471466) (xy 368.95024 -106.471466) (xy 368.95024 -106.852466) (xy 368.44224 -106.852466)
				)
			)
		)
	)
	(footprint ""
		(layer "F.Cu")
		(at 408.178 -126.238)
		(property "Reference" "C8B9"
			(at 0 0 0)
			(layer "F.SilkS")
			(hide yes)
			(effects
				(font
					(size 1.27 1.27)
				)
			)
		)
		(property "Value" ""
			(at 0 0 0)
			(layer "F.Fab")
			(effects
				(font
					(size 1.27 1.27)
				)
			)
		)
		(duplicate_pad_numbers_are_jumpers no)
		(fp_poly
			(pts
				(xy -0.4953 -0.2032) (xy 0.4953 -0.2032) (xy 0.4953 1.6002) (xy -0.4953 1.6002)
			)
			(stroke
				(width 0)
				(type default)
			)
			(fill no)
			(layer "F.CrtYd")
		)
		(fp_line
			(start -0.4953 -0.2032)
			(end 0.4953 -0.2032)
			(stroke
				(width 0.1)
				(type default)
			)
			(layer "F.Fab")
		)
		(fp_line
			(start -0.4953 1.6002)
			(end -0.4953 -0.2032)
			(stroke
				(width 0.1)
				(type default)
			)
			(layer "F.Fab")
		)
		(fp_line
			(start 0.4953 -0.2032)
			(end 0.4953 1.6002)
			(stroke
				(width 0.1)
				(type default)
			)
			(layer "F.Fab")
		)
		(fp_line
			(start 0.4953 1.6002)
			(end -0.4953 1.6002)
			(stroke
				(width 0.1)
				(type default)
			)
			(layer "F.Fab")
		)
		(pad "1" smd rect
			(at 0 0)
			(size 0.762 0.889)
			(layers "F.Cu" "F.Mask" "F.Paste")
			(net "P1V05_PCH_STBY")
		)
		(pad "2" smd rect
			(at 0 1.397)
			(size 0.762 0.889)
			(layers "F.Cu" "F.Mask" "F.Paste")
			(net "GND")
		)
		(zone
			(layer "F.Cu")
			(hatch none 0.5)
			(connect_pads
				(clearance 0)
			)
			(min_thickness 0.25)
			(keepout
				(tracks not_allowed)
				(vias allowed)
				(pads allowed)
				(copperpour not_allowed)
				(footprints allowed)
			)
			(placement
				(enabled no)
				(sheetname "")
			)
			(fill
				(thermal_gap 0.5)
				(thermal_bridge_width 0.5)
				(island_removal_mode 0)
			)
			(polygon
				(pts
					(xy 407.797 -125.7935) (xy 408.559 -125.7935) (xy 408.559 -125.2855) (xy 407.797 -125.2855)
				)
			)
		)
	)
	(footprint ""
		(layer "F.Cu")
		(at 324.5485 -120.396 90)
		(property "Reference" "C6B10"
			(at -0.8382 -0.67818 90)
			(unlocked yes)
			(layer "F.SilkS")
			(effects
				(font
					(size 0.4064 0.254)
					(thickness 0.1524)
				)
				(justify left)
			)
		)
		(property "Value" ""
			(at 0 0 90)
			(layer "F.Fab")
			(effects
				(font
					(size 1.27 1.27)
				)
			)
		)
		(duplicate_pad_numbers_are_jumpers no)
		(fp_poly
			(pts
				(xy 0.3048 -0.1016) (xy 0.3048 0.9906) (xy -0.3048 0.9906) (xy -0.3048 -0.1016)
			)
			(stroke
				(width 0)
				(type default)
			)
			(fill no)
			(layer "F.CrtYd")
		)
		(fp_line
			(start 0.3048 -0.1016)
			(end -0.3048 -0.1016)
			(stroke
				(width 0.1)
				(type default)
			)
			(layer "F.Fab")
		)
		(fp_line
			(start -0.3048 -0.1016)
			(end -0.3048 0.9906)
			(stroke
				(width 0.1)
				(type default)
			)
			(layer "F.Fab")
		)
		(fp_line
			(start 0.3048 0.9906)
			(end 0.3048 -0.1016)
			(stroke
				(width 0.1)
				(type default)
			)
			(layer "F.Fab")
		)
		(fp_line
			(start -0.3048 0.9906)
			(end 0.3048 0.9906)
			(stroke
				(width 0.1)
				(type default)
			)
			(layer "F.Fab")
		)
		(pad "1" smd rect
			(at 0 0 90)
			(size 0.508 0.508)
			(layers "F.Cu" "F.Mask" "F.Paste")
			(net "P3E_CPU0_PE1_PCH_TXP<13>")
		)
		(pad "2" smd rect
			(at 0 0.889 90)
			(size 0.508 0.508)
			(layers "F.Cu" "F.Mask" "F.Paste")
			(net "P3E_CPU0_PE1_PCH_C_TXP<13>")
		)
		(zone
			(layer "F.Cu")
			(hatch none 0.5)
			(connect_pads
				(clearance 0)
			)
			(min_thickness 0.25)
			(keepout
				(tracks allowed)
				(vias not_allowed)
				(pads allowed)
				(copperpour not_allowed)
				(footprints allowed)
			)
			(placement
				(enabled no)
				(sheetname "")
			)
			(fill
				(thermal_gap 0.5)
				(thermal_bridge_width 0.5)
				(island_removal_mode 0)
			)
			(polygon
				(pts
					(xy 324.8025 -120.142) (xy 324.8025 -120.65) (xy 325.1835 -120.65) (xy 325.1835 -120.142)
				)
			)
		)
	)
	(footprint ""
		(layer "F.Cu")
		(at 479.6155 -142.875 90)
		(property "Reference" "C1L10"
			(at 0 0 90)
			(layer "F.SilkS")
			(hide yes)
			(effects
				(font
					(size 1.27 1.27)
				)
			)
		)
		(property "Value" ""
			(at 0 0 90)
			(layer "F.Fab")
			(effects
				(font
					(size 1.27 1.27)
				)
			)
		)
		(duplicate_pad_numbers_are_jumpers no)
		(fp_poly
			(pts
				(xy 0.3048 -0.1016) (xy 0.3048 0.9906) (xy -0.3048 0.9906) (xy -0.3048 -0.1016)
			)
			(stroke
				(width 0)
				(type default)
			)
			(fill no)
			(layer "F.CrtYd")
		)
		(fp_line
			(start 0.3048 -0.1016)
			(end -0.3048 -0.1016)
			(stroke
				(width 0.1)
				(type default)
			)
			(layer "F.Fab")
		)
		(fp_line
			(start -0.3048 -0.1016)
			(end -0.3048 0.9906)
			(stroke
				(width 0.1)
				(type default)
			)
			(layer "F.Fab")
		)
		(fp_line
			(start 0.3048 0.9906)
			(end 0.3048 -0.1016)
			(stroke
				(width 0.1)
				(type default)
			)
			(layer "F.Fab")
		)
		(fp_line
			(start -0.3048 0.9906)
			(end 0.3048 0.9906)
			(stroke
				(width 0.1)
				(type default)
			)
			(layer "F.Fab")
		)
		(pad "1" smd rect
			(at 0 0 90)
			(size 0.508 0.508)
			(layers "F.Cu" "F.Mask" "F.Paste")
			(net "FP_RST_BTN_R_N")
		)
		(pad "2" smd rect
			(at 0 0.889 90)
			(size 0.508 0.508)
			(layers "F.Cu" "F.Mask" "F.Paste")
			(net "GND")
		)
		(zone
			(layer "F.Cu")
			(hatch none 0.5)
			(connect_pads
				(clearance 0)
			)
			(min_thickness 0.25)
			(keepout
				(tracks allowed)
				(vias not_allowed)
				(pads allowed)
				(copperpour not_allowed)
				(footprints allowed)
			)
			(placement
				(enabled no)
				(sheetname "")
			)
			(fill
				(thermal_gap 0.5)
				(thermal_bridge_width 0.5)
				(island_removal_mode 0)
			)
			(polygon
				(pts
					(xy 479.8695 -142.621) (xy 479.8695 -143.129) (xy 480.2505 -143.129) (xy 480.2505 -142.621)
				)
			)
		)
		(zone
			(layer "F.Cu")
			(hatch none 0.5)
			(connect_pads
				(clearance 0)
			)
			(min_thickness 0.25)
			(keepout
				(tracks not_allowed)
				(vias allowed)
				(pads allowed)
				(copperpour not_allowed)
				(footprints allowed)
			)
			(placement
				(enabled no)
				(sheetname "")
			)
			(fill
				(thermal_gap 0.5)
				(thermal_bridge_width 0.5)
				(island_removal_mode 0)
			)
			(polygon
				(pts
					(xy 480.2505 -142.621) (xy 480.2505 -143.129) (xy 479.8695 -143.129) (xy 479.8695 -142.621)
				)
			)
		)
	)
	(footprint ""
		(layer "F.Cu")
		(at 351.5868 -8.0518 180)
		(property "Reference" "CT49"
			(at -1.1684 2.18567 180)
			(unlocked yes)
			(layer "F.SilkS")
			(effects
				(font
					(size 0.7874 0.5842)
					(thickness 0.1524)
				)
				(justify left)
			)
		)
		(property "Value" ""
			(at 0 0 180)
			(layer "F.Fab")
			(effects
				(font
					(size 1.27 1.27)
				)
			)
		)
		(duplicate_pad_numbers_are_jumpers no)
		(fp_poly
			(pts
				(xy 0.3048 -0.1016) (xy 0.3048 0.9906) (xy -0.3048 0.9906) (xy -0.3048 -0.1016)
			)
			(stroke
				(width 0)
				(type default)
			)
			(fill no)
			(layer "F.CrtYd")
		)
		(fp_line
			(start 0.3048 0.9906)
			(end 0.3048 -0.1016)
			(stroke
				(width 0.1)
				(type default)
			)
			(layer "F.Fab")
		)
		(fp_line
			(start 0.3048 -0.1016)
			(end -0.3048 -0.1016)
			(stroke
				(width 0.1)
				(type default)
			)
			(layer "F.Fab")
		)
		(fp_line
			(start -0.3048 0.9906)
			(end 0.3048 0.9906)
			(stroke
				(width 0.1)
				(type default)
			)
			(layer "F.Fab")
		)
		(fp_line
			(start -0.3048 -0.1016)
			(end -0.3048 0.9906)
			(stroke
				(width 0.1)
				(type default)
			)
			(layer "F.Fab")
		)
		(pad "1" smd rect
			(at 0 0 180)
			(size 0.508 0.508)
			(layers "F.Cu" "F.Mask" "F.Paste")
			(net "A_TSENSE_PVDDQ_ABC")
		)
		(pad "2" smd rect
			(at 0 0.889 180)
			(size 0.508 0.508)
			(layers "F.Cu" "F.Mask" "F.Paste")
			(net "GND")
		)
		(zone
			(layer "F.Cu")
			(hatch none 0.5)
			(connect_pads
				(clearance 0)
			)
			(min_thickness 0.25)
			(keepout
				(tracks not_allowed)
				(vias allowed)
				(pads allowed)
				(copperpour not_allowed)
				(footprints allowed)
			)
			(placement
				(enabled no)
				(sheetname "")
			)
			(fill
				(thermal_gap 0.5)
				(thermal_bridge_width 0.5)
				(island_removal_mode 0)
			)
			(polygon
				(pts
					(xy 351.8408 -8.6868) (xy 351.3328 -8.6868) (xy 351.3328 -8.3058) (xy 351.8408 -8.3058)
				)
			)
		)
		(zone
			(layer "F.Cu")
			(hatch none 0.5)
			(connect_pads
				(clearance 0)
			)
			(min_thickness 0.25)
			(keepout
				(tracks allowed)
				(vias not_allowed)
				(pads allowed)
				(copperpour not_allowed)
				(footprints allowed)
			)
			(placement
				(enabled no)
				(sheetname "")
			)
			(fill
				(thermal_gap 0.5)
				(thermal_bridge_width 0.5)
				(island_removal_mode 0)
			)
			(polygon
				(pts
					(xy 351.8408 -8.3058) (xy 351.3328 -8.3058) (xy 351.3328 -8.6868) (xy 351.8408 -8.6868)
				)
			)
		)
	)
	(footprint ""
		(layer "F.Cu")
		(at 413.3342 -114.2492 -90)
		(property "Reference" "R7W10"
			(at -0.8382 -0.67818 270)
			(unlocked yes)
			(layer "F.SilkS")
			(effects
				(font
					(size 0.4064 0.254)
					(thickness 0.1524)
				)
				(justify left)
			)
		)
		(property "Value" ""
			(at 0 0 270)
			(layer "F.Fab")
			(effects
				(font
					(size 1.27 1.27)
				)
			)
		)
		(duplicate_pad_numbers_are_jumpers no)
		(fp_poly
			(pts
				(xy -0.2794 -0.1016) (xy 0.2794 -0.1016) (xy 0.2794 0.9906) (xy -0.2794 0.9906)
			)
			(stroke
				(width 0)
				(type default)
			)
			(fill no)
			(layer "F.CrtYd")
		)
		(fp_line
			(start -0.2794 0.9906)
			(end 0.2794 0.9906)
			(stroke
				(width 0.1)
				(type default)
			)
			(layer "F.Fab")
		)
		(fp_line
			(start 0.2794 0.9906)
			(end 0.2794 -0.1016)
			(stroke
				(width 0.1)
				(type default)
			)
			(layer "F.Fab")
		)
		(fp_line
			(start -0.2794 -0.1016)
			(end -0.2794 0.9906)
			(stroke
				(width 0.1)
				(type default)
			)
			(layer "F.Fab")
		)
		(fp_line
			(start 0.2794 -0.1016)
			(end -0.2794 -0.1016)
			(stroke
				(width 0.1)
				(type default)
			)
			(layer "F.Fab")
		)
		(pad "1" smd rect
			(at 0 0 270)
			(size 0.508 0.508)
			(layers "F.Cu" "F.Mask" "F.Paste")
			(net "FM_CPU0_RC_ERROR_N")
		)
		(pad "2" smd rect
			(at 0 0.889 270)
			(size 0.508 0.508)
			(layers "F.Cu" "F.Mask" "F.Paste")
			(net "FM_CPU0_RC_ERROR_R1_N")
		)
		(zone
			(layer "F.Cu")
			(hatch none 0.5)
			(connect_pads
				(clearance 0)
			)
			(min_thickness 0.25)
			(keepout
				(tracks not_allowed)
				(vias allowed)
				(pads allowed)
				(copperpour not_allowed)
				(footprints allowed)
			)
			(placement
				(enabled no)
				(sheetname "")
			)
			(fill
				(thermal_gap 0.5)
				(thermal_bridge_width 0.5)
				(island_removal_mode 0)
			)
			(polygon
				(pts
					(xy 412.6992 -114.5032) (xy 412.6992 -113.9952) (xy 413.0802 -113.9952) (xy 413.0802 -114.5032)
				)
			)
		)
		(zone
			(layer "F.Cu")
			(hatch none 0.5)
			(connect_pads
				(clearance 0)
			)
			(min_thickness 0.25)
			(keepout
				(tracks allowed)
				(vias not_allowed)
				(pads allowed)
				(copperpour not_allowed)
				(footprints allowed)
			)
			(placement
				(enabled no)
				(sheetname "")
			)
			(fill
				(thermal_gap 0.5)
				(thermal_bridge_width 0.5)
				(island_removal_mode 0)
			)
			(polygon
				(pts
					(xy 413.0802 -114.5032) (xy 413.0802 -113.9952) (xy 412.6992 -113.9952) (xy 412.6992 -114.5032)
				)
			)
		)
	)
)
